#ISCELL
  logical_power cad_note *
  *
#ISCELL
  pure_quanta quanta_title_block_c *
  *
#CELL
  pure_quanta q_res *
  page85_i1
#ISCELL
  standard offpage *
  page85_i10
#ISCELL
  standard tap *
  page85_i100
#ISCELL
  standard tap *
  page85_i101
#ISCELL
  standard tap *
  page85_i102
#ISCELL
  standard tap *
  page85_i103
#ISCELL
  standard tap *
  page85_i104
#ISCELL
  standard tap *
  page85_i105
#ISCELL
  standard tap *
  page85_i106
#ISCELL
  standard tap *
  page85_i107
#ISCELL
  standard tap *
  page85_i108
#ISCELL
  standard tap *
  page85_i109
#ISCELL
  logical_power vcc_core *
  page85_i11
#ISCELL
  standard tap *
  page85_i110
#ISCELL
  standard tap *
  page85_i111
#ISCELL
  standard offpage *
  page85_i112
#ISCELL
  standard tap *
  page85_i113
#ISCELL
  standard tap *
  page85_i114
#ISCELL
  standard tap *
  page85_i115
#ISCELL
  standard tap *
  page85_i116
#ISCELL
  standard tap *
  page85_i117
#ISCELL
  standard tap *
  page85_i118
#ISCELL
  logical_power universal_gnd *
  page85_i119
#ISCELL
  standard offpage *
  page85_i12
#ISCELL
  logical_power universal_gnd *
  page85_i120
#CELL
  pure_quanta q_cap *
  page85_i121
#ISCELL
  logical_power vcc_core *
  page85_i122
#ISCELL
  standard offpage *
  page85_i123
#CELL
  pure_quanta q_cap *
  page85_i125
#ISCELL
  logical_power vcc_core *
  page85_i126
#CELL
  pure_quanta q_cap *
  page85_i127
#ISCELL
  standard tap *
  page85_i128
#ISCELL
  standard tap *
  page85_i129
#ISCELL
  standard offpage *
  page85_i13
#ISCELL
  standard tap *
  page85_i130
#ISCELL
  standard tap *
  page85_i131
#ISCELL
  standard tap *
  page85_i132
#ISCELL
  standard tap *
  page85_i133
#ISCELL
  standard tap *
  page85_i134
#ISCELL
  standard tap *
  page85_i135
#ISCELL
  standard tap *
  page85_i136
#ISCELL
  standard tap *
  page85_i137
#ISCELL
  standard tap *
  page85_i138
#ISCELL
  standard tap *
  page85_i139
#ISCELL
  standard offpage *
  page85_i14
#ISCELL
  standard tap *
  page85_i140
#ISCELL
  standard tap *
  page85_i141
#ISCELL
  standard tap *
  page85_i142
#ISCELL
  standard tap *
  page85_i143
#ISCELL
  standard tap *
  page85_i144
#ISCELL
  standard tap *
  page85_i145
#ISCELL
  standard tap *
  page85_i146
#ISCELL
  standard tap *
  page85_i147
#ISCELL
  standard tap *
  page85_i148
#ISCELL
  standard tap *
  page85_i149
#ISCELL
  standard offpage *
  page85_i15
#ISCELL
  standard tap *
  page85_i150
#ISCELL
  standard tap *
  page85_i151
#ISCELL
  standard tap *
  page85_i152
#ISCELL
  standard tap *
  page85_i153
#ISCELL
  standard tap *
  page85_i154
#ISCELL
  standard tap *
  page85_i155
#ISCELL
  standard tap *
  page85_i156
#ISCELL
  standard tap *
  page85_i157
#ISCELL
  standard tap *
  page85_i158
#ISCELL
  standard tap *
  page85_i159
#ISCELL
  standard offpage *
  page85_i16
#ISCELL
  standard tap *
  page85_i160
#ISCELL
  standard tap *
  page85_i161
#ISCELL
  standard tap *
  page85_i162
#ISCELL
  standard tap *
  page85_i163
#ISCELL
  standard tap *
  page85_i164
#ISCELL
  standard offpage *
  page85_i165
#ISCELL
  standard offpage *
  page85_i166
#ISCELL
  standard offpage *
  page85_i167
#ISCELL
  standard tap *
  page85_i168
#ISCELL
  standard tap *
  page85_i169
#ISCELL
  standard offpage *
  page85_i17
#ISCELL
  standard tap *
  page85_i170
#ISCELL
  standard offpage *
  page85_i171
#ISCELL
  standard offpage *
  page85_i172
#ISCELL
  logical_power universal_gnd *
  page85_i173
#CELL
  pure_quanta sconn288_adr50017p087cc *
  page85_i174
#ISCELL
  logical_power universal_gnd *
  page85_i175
#ISCELL
  logical_power vcc_core *
  page85_i176
#ISCELL
  standard offpage *
  page85_i177
#CELL
  pure_quanta sconn288_adr50017p087cc *
  page85_i178
#ISCELL
  standard offpage *
  page85_i179
#ISCELL
  standard offpage *
  page85_i18
#CELL
  pure_quanta q_res *
  page85_i180
#ISCELL
  standard offpage *
  page85_i19
#ISCELL
  logical_power universal_gnd *
  page85_i2
#ISCELL
  standard offpage *
  page85_i20
#ISCELL
  standard offpage *
  page85_i21
#ISCELL
  standard offpage *
  page85_i22
#CELL
  pure_quanta sconn288_adr50017p087cc *
  page85_i23
#ISCELL
  standard tap *
  page85_i24
#ISCELL
  standard tap *
  page85_i25
#ISCELL
  standard tap *
  page85_i26
#ISCELL
  standard tap *
  page85_i27
#ISCELL
  standard tap *
  page85_i28
#ISCELL
  standard tap *
  page85_i29
#ISCELL
  standard offpage *
  page85_i3
#ISCELL
  standard tap *
  page85_i30
#ISCELL
  standard tap *
  page85_i31
#ISCELL
  standard tap *
  page85_i32
#ISCELL
  standard tap *
  page85_i33
#ISCELL
  standard tap *
  page85_i34
#ISCELL
  standard tap *
  page85_i35
#ISCELL
  standard tap *
  page85_i36
#ISCELL
  standard tap *
  page85_i37
#ISCELL
  standard tap *
  page85_i38
#ISCELL
  standard tap *
  page85_i39
#ISCELL
  standard offpage *
  page85_i4
#ISCELL
  standard tap *
  page85_i40
#ISCELL
  standard tap *
  page85_i41
#ISCELL
  standard tap *
  page85_i42
#ISCELL
  standard tap *
  page85_i43
#ISCELL
  standard tap *
  page85_i44
#ISCELL
  standard tap *
  page85_i45
#ISCELL
  standard tap *
  page85_i46
#ISCELL
  standard tap *
  page85_i47
#ISCELL
  standard tap *
  page85_i48
#ISCELL
  standard tap *
  page85_i49
#ISCELL
  standard offpage *
  page85_i5
#ISCELL
  standard tap *
  page85_i50
#ISCELL
  standard tap *
  page85_i51
#ISCELL
  standard tap *
  page85_i52
#ISCELL
  standard tap *
  page85_i53
#ISCELL
  standard tap *
  page85_i54
#ISCELL
  standard tap *
  page85_i55
#ISCELL
  standard tap *
  page85_i56
#ISCELL
  standard tap *
  page85_i57
#ISCELL
  standard tap *
  page85_i58
#ISCELL
  standard tap *
  page85_i59
#ISCELL
  standard tap *
  page85_i60
#ISCELL
  standard tap *
  page85_i61
#ISCELL
  standard tap *
  page85_i62
#ISCELL
  standard tap *
  page85_i63
#ISCELL
  standard tap *
  page85_i64
#ISCELL
  standard tap *
  page85_i65
#ISCELL
  standard tap *
  page85_i66
#ISCELL
  standard tap *
  page85_i67
#ISCELL
  standard tap *
  page85_i68
#ISCELL
  standard tap *
  page85_i69
#ISCELL
  standard offpage *
  page85_i7
#ISCELL
  standard tap *
  page85_i70
#ISCELL
  standard tap *
  page85_i71
#ISCELL
  standard tap *
  page85_i72
#ISCELL
  standard tap *
  page85_i73
#ISCELL
  standard tap *
  page85_i74
#ISCELL
  standard tap *
  page85_i75
#ISCELL
  standard tap *
  page85_i76
#ISCELL
  standard tap *
  page85_i77
#ISCELL
  standard tap *
  page85_i78
#ISCELL
  standard tap *
  page85_i79
#ISCELL
  standard offpage *
  page85_i8
#ISCELL
  standard tap *
  page85_i80
#ISCELL
  standard tap *
  page85_i81
#ISCELL
  standard tap *
  page85_i82
#ISCELL
  standard tap *
  page85_i83
#ISCELL
  standard tap *
  page85_i84
#ISCELL
  standard tap *
  page85_i85
#ISCELL
  standard tap *
  page85_i86
#ISCELL
  standard tap *
  page85_i87
#ISCELL
  standard tap *
  page85_i88
#ISCELL
  standard tap *
  page85_i89
#ISCELL
  standard offpage *
  page85_i9
#ISCELL
  standard tap *
  page85_i90
#ISCELL
  standard tap *
  page85_i91
#ISCELL
  standard tap *
  page85_i92
#ISCELL
  standard tap *
  page85_i93
#ISCELL
  standard tap *
  page85_i94
#ISCELL
  standard tap *
  page85_i95
#ISCELL
  standard tap *
  page85_i96
#ISCELL
  standard tap *
  page85_i97
#ISCELL
  standard tap *
  page85_i98
#ISCELL
  standard tap *
  page85_i99
